(kicad_pcb
	(version 20260206)
	(generator "pcbnew")
	(generator_version "10.0")
	(general
		(thickness 1.6)
		(legacy_teardrops no)
	)
	(paper "A4")
	(title_block
		(title "04192023_DAF0TMB3IC0_F0TG_MB_C_brd_V02_OCP.brd")
		(comment 1 "Grand Teton / footprints 1469-1475 of 8354")
	)
	(layers
		(0 "F.Cu" signal "TOP")
		(4 "In1.Cu" signal "GND")
		(6 "In2.Cu" signal "IN1")
		(8 "In3.Cu" signal "GND1")
		(10 "In4.Cu" signal "IN2")
		(12 "In5.Cu" signal "GND2")
		(14 "In6.Cu" signal "IN3")
		(16 "In7.Cu" signal "GND3")
		(18 "In8.Cu" signal "VCC")
		(20 "In9.Cu" signal "VCC1")
		(22 "In10.Cu" signal "GND4")
		(24 "In11.Cu" signal "IN4")
		(26 "In12.Cu" signal "GND5")
		(28 "In13.Cu" signal "IN5")
		(30 "In14.Cu" signal "GND6")
		(32 "In15.Cu" signal "IN6")
		(34 "In16.Cu" signal "GND7")
		(2 "B.Cu" signal "BOTTOM")
		(9 "F.Adhes" user "F.Adhesive")
		(11 "B.Adhes" user "B.Adhesive")
		(13 "F.Paste" user "Package Geometry/Pastemask Top")
		(15 "B.Paste" user "Package Geometry/Pastemask Bottom")
		(5 "F.SilkS" user "Ref Des/Silkscreen Top")
		(7 "B.SilkS" user "Ref Des/Silkscreen Bottom")
		(1 "F.Mask" user "Board Geometry/Soldermask Top")
		(3 "B.Mask" user "Board Geometry/Soldermask Bottom")
		(17 "Dwgs.User" user "User.Drawings")
		(19 "Cmts.User" user "User.Comments")
		(21 "Eco1.User" user "User.Eco1")
		(23 "Eco2.User" user "User.Eco2")
		(25 "Edge.Cuts" user "Board Geometry/Outline")
		(27 "Margin" user)
		(31 "F.CrtYd" user "Package Geometry/Place Bound Top")
		(29 "B.CrtYd" user "Package Geometry/Place Bound Bottom")
		(35 "F.Fab" user "Ref Des/Assembly Top")
		(33 "B.Fab" user "Ref Des/Assembly Bottom")
	)
	(footprint ""
		(layer "F.Cu")
		(at 259.834126 -97.476056 180)
		(property "Reference" "R1634"
			(at 0 0 180)
			(layer "F.SilkS")
			(hide yes)
			(effects
				(font
					(size 1.27 1.27)
				)
			)
		)
		(property "Value" ""
			(at 0 0 180)
			(layer "F.Fab")
			(effects
				(font
					(size 1.27 1.27)
				)
			)
		)
		(duplicate_pad_numbers_are_jumpers no)
		(fp_line
			(start 0.7874 0.4064)
			(end -0.7874 0.4064)
			(stroke
				(width 0.1524)
				(type default)
			)
			(layer "F.SilkS")
		)
		(fp_line
			(start 0.7874 -0.4064)
			(end 0.7874 0.4064)
			(stroke
				(width 0.1524)
				(type default)
			)
			(layer "F.SilkS")
		)
		(fp_line
			(start -0.7874 0.4064)
			(end -0.7874 -0.4064)
			(stroke
				(width 0.1524)
				(type default)
			)
			(layer "F.SilkS")
		)
		(fp_line
			(start -0.7874 -0.4064)
			(end 0.7874 -0.4064)
			(stroke
				(width 0.1524)
				(type default)
			)
			(layer "F.SilkS")
		)
		(fp_line
			(start 0.67945 0.3048)
			(end 0.120396 0.3048)
			(stroke
				(width 0.1)
				(type default)
			)
			(layer "F.Fab")
		)
		(fp_line
			(start 0.67945 -0.3048)
			(end 0.67945 0.3048)
			(stroke
				(width 0.1)
				(type default)
			)
			(layer "F.Fab")
		)
		(fp_line
			(start 0.12065 -0.2794)
			(end 0.12065 -0.3048)
			(stroke
				(width 0.1)
				(type default)
			)
			(layer "F.Fab")
		)
		(fp_line
			(start 0.12065 -0.3048)
			(end 0.67945 -0.3048)
			(stroke
				(width 0.1)
				(type default)
			)
			(layer "F.Fab")
		)
		(fp_line
			(start 0.120396 0.3048)
			(end 0.120396 0.2794)
			(stroke
				(width 0.1)
				(type default)
			)
			(layer "F.Fab")
		)
		(fp_line
			(start 0.120396 0.2794)
			(end -0.12065 0.2794)
			(stroke
				(width 0.1)
				(type default)
			)
			(layer "F.Fab")
		)
		(fp_line
			(start -0.12065 0.3048)
			(end -0.67945 0.3048)
			(stroke
				(width 0.1)
				(type default)
			)
			(layer "F.Fab")
		)
		(fp_line
			(start -0.12065 0.2794)
			(end -0.12065 0.3048)
			(stroke
				(width 0.1)
				(type default)
			)
			(layer "F.Fab")
		)
		(fp_line
			(start -0.12065 -0.2794)
			(end 0.12065 -0.2794)
			(stroke
				(width 0.1)
				(type default)
			)
			(layer "F.Fab")
		)
		(fp_line
			(start -0.12065 -0.305054)
			(end -0.12065 -0.2794)
			(stroke
				(width 0.1)
				(type default)
			)
			(layer "F.Fab")
		)
		(fp_line
			(start -0.67945 0.3048)
			(end -0.67945 -0.305054)
			(stroke
				(width 0.1)
				(type default)
			)
			(layer "F.Fab")
		)
		(fp_line
			(start -0.67945 -0.305054)
			(end -0.12065 -0.305054)
			(stroke
				(width 0.1)
				(type default)
			)
			(layer "F.Fab")
		)
		(pad "1" smd circle
			(at -0.40005 0 180)
			(size 0 0)
			(layers "F.Cu" "F.Mask" "F.Paste")
			(net "JTAG_TMS_R")
		)
		(pad "2" smd circle
			(at 0.40005 0 180)
			(size 0 0)
			(layers "F.Cu" "F.Mask" "F.Paste")
			(net "JTAG_TMS")
		)
	)
	(footprint ""
		(layer "F.Cu")
		(at 57.872884 -408.517344 -90)
		(property "Reference" "C6635"
			(at 0 0 270)
			(layer "F.SilkS")
			(hide yes)
			(effects
				(font
					(size 1.27 1.27)
				)
			)
		)
		(property "Value" ""
			(at 0 0 270)
			(layer "F.Fab")
			(effects
				(font
					(size 1.27 1.27)
				)
			)
		)
		(duplicate_pad_numbers_are_jumpers no)
		(fp_line
			(start -0.299974 0.150114)
			(end -0.299974 -0.150114)
			(stroke
				(width 0.1)
				(type default)
			)
			(layer "F.Fab")
		)
		(fp_line
			(start 0.299974 0.150114)
			(end -0.299974 0.150114)
			(stroke
				(width 0.1)
				(type default)
			)
			(layer "F.Fab")
		)
		(fp_line
			(start -0.299974 -0.150114)
			(end 0.299974 -0.150114)
			(stroke
				(width 0.1)
				(type default)
			)
			(layer "F.Fab")
		)
		(fp_line
			(start 0.299974 -0.150114)
			(end 0.299974 0.150114)
			(stroke
				(width 0.1)
				(type default)
			)
			(layer "F.Fab")
		)
		(pad "1" smd rect
			(at -0.2667 0 270)
			(size 0.3048 0.381)
			(layers "F.Cu" "F.Mask" "F.Paste")
			(net "P5E_CPU1_P0_TX_BUF_C_DP<3>")
		)
		(pad "2" smd rect
			(at 0.2667 0 270)
			(size 0.3048 0.381)
			(layers "F.Cu" "F.Mask" "F.Paste")
			(net "P5E_CPU1_P0_TX_BUF_DP<3>")
		)
	)
	(footprint ""
		(layer "F.Cu")
		(at 279.513792 -113.62817 180)
		(property "Reference" "R3526"
			(at 0 0 180)
			(layer "F.SilkS")
			(hide yes)
			(effects
				(font
					(size 1.27 1.27)
				)
			)
		)
		(property "Value" ""
			(at 0 0 180)
			(layer "F.Fab")
			(effects
				(font
					(size 1.27 1.27)
				)
			)
		)
		(duplicate_pad_numbers_are_jumpers no)
		(fp_line
			(start 0.7874 0.4064)
			(end -0.7874 0.4064)
			(stroke
				(width 0.1524)
				(type default)
			)
			(layer "F.SilkS")
		)
		(fp_line
			(start 0.7874 -0.4064)
			(end 0.7874 0.4064)
			(stroke
				(width 0.1524)
				(type default)
			)
			(layer "F.SilkS")
		)
		(fp_line
			(start -0.7874 0.4064)
			(end -0.7874 -0.4064)
			(stroke
				(width 0.1524)
				(type default)
			)
			(layer "F.SilkS")
		)
		(fp_line
			(start -0.7874 -0.4064)
			(end 0.7874 -0.4064)
			(stroke
				(width 0.1524)
				(type default)
			)
			(layer "F.SilkS")
		)
		(fp_line
			(start 0.67945 0.3048)
			(end 0.120396 0.3048)
			(stroke
				(width 0.1)
				(type default)
			)
			(layer "F.Fab")
		)
		(fp_line
			(start 0.67945 -0.3048)
			(end 0.67945 0.3048)
			(stroke
				(width 0.1)
				(type default)
			)
			(layer "F.Fab")
		)
		(fp_line
			(start 0.12065 -0.2794)
			(end 0.12065 -0.3048)
			(stroke
				(width 0.1)
				(type default)
			)
			(layer "F.Fab")
		)
		(fp_line
			(start 0.12065 -0.3048)
			(end 0.67945 -0.3048)
			(stroke
				(width 0.1)
				(type default)
			)
			(layer "F.Fab")
		)
		(fp_line
			(start 0.120396 0.3048)
			(end 0.120396 0.2794)
			(stroke
				(width 0.1)
				(type default)
			)
			(layer "F.Fab")
		)
		(fp_line
			(start 0.120396 0.2794)
			(end -0.12065 0.2794)
			(stroke
				(width 0.1)
				(type default)
			)
			(layer "F.Fab")
		)
		(fp_line
			(start -0.12065 0.3048)
			(end -0.67945 0.3048)
			(stroke
				(width 0.1)
				(type default)
			)
			(layer "F.Fab")
		)
		(fp_line
			(start -0.12065 0.2794)
			(end -0.12065 0.3048)
			(stroke
				(width 0.1)
				(type default)
			)
			(layer "F.Fab")
		)
		(fp_line
			(start -0.12065 -0.2794)
			(end 0.12065 -0.2794)
			(stroke
				(width 0.1)
				(type default)
			)
			(layer "F.Fab")
		)
		(fp_line
			(start -0.12065 -0.305054)
			(end -0.12065 -0.2794)
			(stroke
				(width 0.1)
				(type default)
			)
			(layer "F.Fab")
		)
		(fp_line
			(start -0.67945 0.3048)
			(end -0.67945 -0.305054)
			(stroke
				(width 0.1)
				(type default)
			)
			(layer "F.Fab")
		)
		(fp_line
			(start -0.67945 -0.305054)
			(end -0.12065 -0.305054)
			(stroke
				(width 0.1)
				(type default)
			)
			(layer "F.Fab")
		)
		(pad "1" smd circle
			(at -0.40005 0 180)
			(size 0 0)
			(layers "F.Cu" "F.Mask" "F.Paste")
			(net "SMB_PCIE0_3V3AUX_SCL_R5")
		)
		(pad "2" smd circle
			(at 0.40005 0 180)
			(size 0 0)
			(layers "F.Cu" "F.Mask" "F.Paste")
			(net "SMB_SENSOR_E1S_3V3AUX_SCL")
		)
	)
	(footprint ""
		(layer "F.Cu")
		(at 329.592178 -43.573954 180)
		(property "Reference" "R3005"
			(at 0 0 180)
			(layer "F.SilkS")
			(hide yes)
			(effects
				(font
					(size 1.27 1.27)
				)
			)
		)
		(property "Value" ""
			(at 0 0 180)
			(layer "F.Fab")
			(effects
				(font
					(size 1.27 1.27)
				)
			)
		)
		(duplicate_pad_numbers_are_jumpers no)
		(fp_line
			(start 0.7874 0.4064)
			(end -0.7874 0.4064)
			(stroke
				(width 0.1524)
				(type default)
			)
			(layer "F.SilkS")
		)
		(fp_line
			(start 0.7874 -0.4064)
			(end 0.7874 0.4064)
			(stroke
				(width 0.1524)
				(type default)
			)
			(layer "F.SilkS")
		)
		(fp_line
			(start -0.7874 0.4064)
			(end -0.7874 -0.4064)
			(stroke
				(width 0.1524)
				(type default)
			)
			(layer "F.SilkS")
		)
		(fp_line
			(start -0.7874 -0.4064)
			(end 0.7874 -0.4064)
			(stroke
				(width 0.1524)
				(type default)
			)
			(layer "F.SilkS")
		)
		(fp_line
			(start 0.67945 0.3048)
			(end 0.120396 0.3048)
			(stroke
				(width 0.1)
				(type default)
			)
			(layer "F.Fab")
		)
		(fp_line
			(start 0.67945 -0.3048)
			(end 0.67945 0.3048)
			(stroke
				(width 0.1)
				(type default)
			)
			(layer "F.Fab")
		)
		(fp_line
			(start 0.12065 -0.2794)
			(end 0.12065 -0.3048)
			(stroke
				(width 0.1)
				(type default)
			)
			(layer "F.Fab")
		)
		(fp_line
			(start 0.12065 -0.3048)
			(end 0.67945 -0.3048)
			(stroke
				(width 0.1)
				(type default)
			)
			(layer "F.Fab")
		)
		(fp_line
			(start 0.120396 0.3048)
			(end 0.120396 0.2794)
			(stroke
				(width 0.1)
				(type default)
			)
			(layer "F.Fab")
		)
		(fp_line
			(start 0.120396 0.2794)
			(end -0.12065 0.2794)
			(stroke
				(width 0.1)
				(type default)
			)
			(layer "F.Fab")
		)
		(fp_line
			(start -0.12065 0.3048)
			(end -0.67945 0.3048)
			(stroke
				(width 0.1)
				(type default)
			)
			(layer "F.Fab")
		)
		(fp_line
			(start -0.12065 0.2794)
			(end -0.12065 0.3048)
			(stroke
				(width 0.1)
				(type default)
			)
			(layer "F.Fab")
		)
		(fp_line
			(start -0.12065 -0.2794)
			(end 0.12065 -0.2794)
			(stroke
				(width 0.1)
				(type default)
			)
			(layer "F.Fab")
		)
		(fp_line
			(start -0.12065 -0.305054)
			(end -0.12065 -0.2794)
			(stroke
				(width 0.1)
				(type default)
			)
			(layer "F.Fab")
		)
		(fp_line
			(start -0.67945 0.3048)
			(end -0.67945 -0.305054)
			(stroke
				(width 0.1)
				(type default)
			)
			(layer "F.Fab")
		)
		(fp_line
			(start -0.67945 -0.305054)
			(end -0.12065 -0.305054)
			(stroke
				(width 0.1)
				(type default)
			)
			(layer "F.Fab")
		)
		(pad "1" smd circle
			(at -0.40005 0 180)
			(size 0 0)
			(layers "F.Cu" "F.Mask" "F.Paste")
			(net "P5V")
		)
		(pad "2" smd circle
			(at 0.40005 0 180)
			(size 0 0)
			(layers "F.Cu" "F.Mask" "F.Paste")
			(net "P5V_ADC")
		)
	)
	(footprint ""
		(layer "F.Cu")
		(at 353.900232 -257.455162)
		(property "Reference" "C2606"
			(at 0 0 0)
			(layer "F.SilkS")
			(hide yes)
			(effects
				(font
					(size 1.27 1.27)
				)
			)
		)
		(property "Value" ""
			(at 0 0 0)
			(layer "F.Fab")
			(effects
				(font
					(size 1.27 1.27)
				)
			)
		)
		(duplicate_pad_numbers_are_jumpers no)
		(fp_line
			(start -0.7874 -0.4064)
			(end 0.7874 -0.4064)
			(stroke
				(width 0.1524)
				(type default)
			)
			(layer "F.SilkS")
		)
		(fp_line
			(start -0.7874 0.4064)
			(end -0.7874 -0.4064)
			(stroke
				(width 0.1524)
				(type default)
			)
			(layer "F.SilkS")
		)
		(fp_line
			(start 0.7874 -0.4064)
			(end 0.7874 0.4064)
			(stroke
				(width 0.1524)
				(type default)
			)
			(layer "F.SilkS")
		)
		(fp_line
			(start 0.7874 0.4064)
			(end -0.7874 0.4064)
			(stroke
				(width 0.1524)
				(type default)
			)
			(layer "F.SilkS")
		)
		(fp_line
			(start -0.67945 -0.305054)
			(end -0.12065 -0.305054)
			(stroke
				(width 0.1)
				(type default)
			)
			(layer "F.Fab")
		)
		(fp_line
			(start -0.67945 0.3048)
			(end -0.67945 -0.305054)
			(stroke
				(width 0.1)
				(type default)
			)
			(layer "F.Fab")
		)
		(fp_line
			(start -0.12065 -0.305054)
			(end -0.12065 -0.2794)
			(stroke
				(width 0.1)
				(type default)
			)
			(layer "F.Fab")
		)
		(fp_line
			(start -0.12065 -0.2794)
			(end 0.12065 -0.2794)
			(stroke
				(width 0.1)
				(type default)
			)
			(layer "F.Fab")
		)
		(fp_line
			(start -0.12065 0.2794)
			(end -0.12065 0.3048)
			(stroke
				(width 0.1)
				(type default)
			)
			(layer "F.Fab")
		)
		(fp_line
			(start -0.12065 0.3048)
			(end -0.67945 0.3048)
			(stroke
				(width 0.1)
				(type default)
			)
			(layer "F.Fab")
		)
		(fp_line
			(start 0.120396 0.2794)
			(end -0.12065 0.2794)
			(stroke
				(width 0.1)
				(type default)
			)
			(layer "F.Fab")
		)
		(fp_line
			(start 0.120396 0.3048)
			(end 0.120396 0.2794)
			(stroke
				(width 0.1)
				(type default)
			)
			(layer "F.Fab")
		)
		(fp_line
			(start 0.12065 -0.3048)
			(end 0.67945 -0.3048)
			(stroke
				(width 0.1)
				(type default)
			)
			(layer "F.Fab")
		)
		(fp_line
			(start 0.12065 -0.2794)
			(end 0.12065 -0.3048)
			(stroke
				(width 0.1)
				(type default)
			)
			(layer "F.Fab")
		)
		(fp_line
			(start 0.67945 -0.3048)
			(end 0.67945 0.3048)
			(stroke
				(width 0.1)
				(type default)
			)
			(layer "F.Fab")
		)
		(fp_line
			(start 0.67945 0.3048)
			(end 0.120396 0.3048)
			(stroke
				(width 0.1)
				(type default)
			)
			(layer "F.Fab")
		)
		(pad "1" smd circle
			(at -0.40005 0)
			(size 0 0)
			(layers "F.Cu" "F.Mask" "F.Paste")
			(net "PVDDIO_P0")
		)
		(pad "2" smd circle
			(at 0.40005 0)
			(size 0 0)
			(layers "F.Cu" "F.Mask" "F.Paste")
			(net "GND")
		)
	)
	(footprint ""
		(layer "F.Cu")
		(at 57.738518 -351.10547)
		(property "Reference" "PC623_4"
			(at 0 0 0)
			(layer "F.SilkS")
			(hide yes)
			(effects
				(font
					(size 1.27 1.27)
				)
			)
		)
		(property "Value" ""
			(at 0 0 0)
			(layer "F.Fab")
			(effects
				(font
					(size 1.27 1.27)
				)
			)
		)
		(duplicate_pad_numbers_are_jumpers no)
		(fp_line
			(start -0.7874 -0.4064)
			(end 0.7874 -0.4064)
			(stroke
				(width 0.1524)
				(type default)
			)
			(layer "F.SilkS")
		)
		(fp_line
			(start -0.7874 0.4064)
			(end -0.7874 -0.4064)
			(stroke
				(width 0.1524)
				(type default)
			)
			(layer "F.SilkS")
		)
		(fp_line
			(start 0.7874 -0.4064)
			(end 0.7874 0.4064)
			(stroke
				(width 0.1524)
				(type default)
			)
			(layer "F.SilkS")
		)
		(fp_line
			(start 0.7874 0.4064)
			(end -0.7874 0.4064)
			(stroke
				(width 0.1524)
				(type default)
			)
			(layer "F.SilkS")
		)
		(fp_line
			(start -0.67945 -0.305054)
			(end -0.12065 -0.305054)
			(stroke
				(width 0.1)
				(type default)
			)
			(layer "F.Fab")
		)
		(fp_line
			(start -0.67945 0.3048)
			(end -0.67945 -0.305054)
			(stroke
				(width 0.1)
				(type default)
			)
			(layer "F.Fab")
		)
		(fp_line
			(start -0.12065 -0.305054)
			(end -0.12065 -0.2794)
			(stroke
				(width 0.1)
				(type default)
			)
			(layer "F.Fab")
		)
		(fp_line
			(start -0.12065 -0.2794)
			(end 0.12065 -0.2794)
			(stroke
				(width 0.1)
				(type default)
			)
			(layer "F.Fab")
		)
		(fp_line
			(start -0.12065 0.2794)
			(end -0.12065 0.3048)
			(stroke
				(width 0.1)
				(type default)
			)
			(layer "F.Fab")
		)
		(fp_line
			(start -0.12065 0.3048)
			(end -0.67945 0.3048)
			(stroke
				(width 0.1)
				(type default)
			)
			(layer "F.Fab")
		)
		(fp_line
			(start 0.120396 0.2794)
			(end -0.12065 0.2794)
			(stroke
				(width 0.1)
				(type default)
			)
			(layer "F.Fab")
		)
		(fp_line
			(start 0.120396 0.3048)
			(end 0.120396 0.2794)
			(stroke
				(width 0.1)
				(type default)
			)
			(layer "F.Fab")
		)
		(fp_line
			(start 0.12065 -0.3048)
			(end 0.67945 -0.3048)
			(stroke
				(width 0.1)
				(type default)
			)
			(layer "F.Fab")
		)
		(fp_line
			(start 0.12065 -0.2794)
			(end 0.12065 -0.3048)
			(stroke
				(width 0.1)
				(type default)
			)
			(layer "F.Fab")
		)
		(fp_line
			(start 0.67945 -0.3048)
			(end 0.67945 0.3048)
			(stroke
				(width 0.1)
				(type default)
			)
			(layer "F.Fab")
		)
		(fp_line
			(start 0.67945 0.3048)
			(end 0.120396 0.3048)
			(stroke
				(width 0.1)
				(type default)
			)
			(layer "F.Fab")
		)
		(pad "1" smd circle
			(at -0.40005 0)
			(size 0 0)
			(layers "F.Cu" "F.Mask" "F.Paste")
			(net "SW_P12V_AUX_PVDDIO_P1_FLT")
		)
		(pad "2" smd circle
			(at 0.40005 0)
			(size 0 0)
			(layers "F.Cu" "F.Mask" "F.Paste")
			(net "GND")
		)
	)
	(footprint ""
		(layer "F.Cu")
		(at 127.64897 -165.194234 90)
		(property "Reference" "PC322_SOP1_2"
			(at 0 0 90)
			(layer "F.SilkS")
			(hide yes)
			(effects
				(font
					(size 1.27 1.27)
				)
			)
		)
		(property "Value" ""
			(at 0 0 90)
			(layer "F.Fab")
			(effects
				(font
					(size 1.27 1.27)
				)
			)
		)
		(duplicate_pad_numbers_are_jumpers no)
		(fp_line
			(start 0.7874 -0.4064)
			(end 0.7874 0.4064)
			(stroke
				(width 0.1524)
				(type default)
			)
			(layer "F.SilkS")
		)
		(fp_line
			(start -0.7874 -0.4064)
			(end 0.7874 -0.4064)
			(stroke
				(width 0.1524)
				(type default)
			)
			(layer "F.SilkS")
		)
		(fp_line
			(start 0.7874 0.4064)
			(end -0.7874 0.4064)
			(stroke
				(width 0.1524)
				(type default)
			)
			(layer "F.SilkS")
		)
		(fp_line
			(start -0.7874 0.4064)
			(end -0.7874 -0.4064)
			(stroke
				(width 0.1524)
				(type default)
			)
			(layer "F.SilkS")
		)
		(fp_line
			(start -0.12065 -0.305054)
			(end -0.12065 -0.2794)
			(stroke
				(width 0.1)
				(type default)
			)
			(layer "F.Fab")
		)
		(fp_line
			(start -0.67945 -0.305054)
			(end -0.12065 -0.305054)
			(stroke
				(width 0.1)
				(type default)
			)
			(layer "F.Fab")
		)
		(fp_line
			(start 0.67945 -0.3048)
			(end 0.67945 0.3048)
			(stroke
				(width 0.1)
				(type default)
			)
			(layer "F.Fab")
		)
		(fp_line
			(start 0.12065 -0.3048)
			(end 0.67945 -0.3048)
			(stroke
				(width 0.1)
				(type default)
			)
			(layer "F.Fab")
		)
		(fp_line
			(start 0.12065 -0.2794)
			(end 0.12065 -0.3048)
			(stroke
				(width 0.1)
				(type default)
			)
			(layer "F.Fab")
		)
		(fp_line
			(start -0.12065 -0.2794)
			(end 0.12065 -0.2794)
			(stroke
				(width 0.1)
				(type default)
			)
			(layer "F.Fab")
		)
		(fp_line
			(start 0.120396 0.2794)
			(end -0.12065 0.2794)
			(stroke
				(width 0.1)
				(type default)
			)
			(layer "F.Fab")
		)
		(fp_line
			(start -0.12065 0.2794)
			(end -0.12065 0.3048)
			(stroke
				(width 0.1)
				(type default)
			)
			(layer "F.Fab")
		)
		(fp_line
			(start 0.67945 0.3048)
			(end 0.120396 0.3048)
			(stroke
				(width 0.1)
				(type default)
			)
			(layer "F.Fab")
		)
		(fp_line
			(start 0.120396 0.3048)
			(end 0.120396 0.2794)
			(stroke
				(width 0.1)
				(type default)
			)
			(layer "F.Fab")
		)
		(fp_line
			(start -0.12065 0.3048)
			(end -0.67945 0.3048)
			(stroke
				(width 0.1)
				(type default)
			)
			(layer "F.Fab")
		)
		(fp_line
			(start -0.67945 0.3048)
			(end -0.67945 -0.305054)
			(stroke
				(width 0.1)
				(type default)
			)
			(layer "F.Fab")
		)
		(pad "1" smd circle
			(at -0.40005 0 90)
			(size 0 0)
			(layers "F.Cu" "F.Mask" "F.Paste")
			(net "PVDDCR_CPU0_P1_PVCC")
		)
		(pad "2" smd circle
			(at 0.40005 0 90)
			(size 0 0)
			(layers "F.Cu" "F.Mask" "F.Paste")
			(net "GND")
		)
	)
)
